# BASEBOARD_FAB2 (Tioga Pass) — schematic netlist excerpt (pin names and nets, part order shuffled) for the footprints in the layout excerpt that follows; sources: Cadence DE-HDL packaged netlist, KiCad conversion of Wiwynn_Tioga_Pass_MB.brd

R1U7  RES  10.0K 1% CHIP  pkg 0402  page 146 : A = GND ; B = PD_SP_ENTEST
C2T11  CAP  0.22UF 16V 10% X7R  pkg 0402  page 185 : A = P3E_PCH_M2_TX_C_DN<1> ; B = P3E_PCH_M2_TX_DN<1>
R2T47  RES  33.2 1% CHIP  pkg 0402  page 101 : A = CLK_25M_CPLD_R ; B = CLK_25M_CPLD

(kicad_pcb
	(version 20260206)
	(generator "pcbnew")
	(generator_version "10.0")
	(general
		(thickness 1.6)
		(legacy_teardrops no)
	)
	(paper "A4")
	(title_block
		(title "Wiwynn_Tioga_Pass_MB.brd")
		(comment 1 "Tioga Pass / footprints 3414-3416 of 4770")
	)
	(layers
		(0 "F.Cu" signal "TOP")
		(4 "In1.Cu" signal "L2GND")
		(6 "In2.Cu" signal "L3")
		(8 "In3.Cu" signal "L4GND")
		(10 "In4.Cu" signal "L5")
		(12 "In5.Cu" signal "L6GND")
		(14 "In6.Cu" signal "L7VCC")
		(16 "In7.Cu" signal "L8VCC")
		(18 "In8.Cu" signal "L9GND")
		(20 "In9.Cu" signal "L10")
		(22 "In10.Cu" signal "L11GND")
		(24 "In11.Cu" signal "L12")
		(26 "In12.Cu" signal "L13GND")
		(2 "B.Cu" signal "BOTTOM")
		(9 "F.Adhes" user "F.Adhesive")
		(11 "B.Adhes" user "B.Adhesive")
		(13 "F.Paste" user "Package Geometry/Pastemask Top")
		(15 "B.Paste" user "Package Geometry/Pastemask Bottom")
		(5 "F.SilkS" user "Ref Des/Silkscreen Top")
		(7 "B.SilkS" user "Ref Des/Silkscreen Bottom")
		(1 "F.Mask" user "Board Geometry/Soldermask Top")
		(3 "B.Mask" user "Board Geometry/Soldermask Bottom")
		(17 "Dwgs.User" user "User.Drawings")
		(19 "Cmts.User" user "User.Comments")
		(21 "Eco1.User" user "User.Eco1")
		(23 "Eco2.User" user "User.Eco2")
		(25 "Edge.Cuts" user "Board Geometry/Outline")
		(27 "Margin" user)
		(31 "F.CrtYd" user "Package Geometry/Place Bound Top")
		(29 "B.CrtYd" user "Package Geometry/Place Bound Bottom")
		(35 "F.Fab" user "Ref Des/Assembly Top")
		(33 "B.Fab" user "Ref Des/Assembly Bottom")
	)
	(footprint ""
		(layer "B.Cu")
		(at 481.965 -32.512 180)
		(property "Reference" "R2T47"
			(at 0 0 0)
			(layer "B.SilkS")
			(hide yes)
			(effects
				(font
					(size 1.27 1.27)
				)
				(justify mirror)
			)
		)
		(property "Value" ""
			(at 0 0 0)
			(layer "B.Fab")
			(effects
				(font
					(size 1.27 1.27)
				)
				(justify mirror)
			)
		)
		(duplicate_pad_numbers_are_jumpers no)
		(fp_poly
			(pts
				(xy 0.2794 -0.1016) (xy -0.2794 -0.1016) (xy -0.2794 0.9906) (xy 0.2794 0.9906)
			)
			(stroke
				(width 0)
				(type default)
			)
			(fill no)
			(layer "B.CrtYd")
		)
		(fp_line
			(start 0.2794 0.9906)
			(end -0.2794 0.9906)
			(stroke
				(width 0.1)
				(type default)
			)
			(layer "B.Fab")
		)
		(fp_line
			(start 0.2794 -0.1016)
			(end 0.2794 0.9906)
			(stroke
				(width 0.1)
				(type default)
			)
			(layer "B.Fab")
		)
		(fp_line
			(start -0.2794 0.9906)
			(end -0.2794 -0.1016)
			(stroke
				(width 0.1)
				(type default)
			)
			(layer "B.Fab")
		)
		(fp_line
			(start -0.2794 -0.1016)
			(end 0.2794 -0.1016)
			(stroke
				(width 0.1)
				(type default)
			)
			(layer "B.Fab")
		)
		(pad "1" smd rect
			(at 0 0)
			(size 0.508 0.508)
			(layers "B.Cu" "B.Mask" "B.Paste")
			(net "CLK_25M_CPLD_R")
		)
		(pad "2" smd rect
			(at 0 0.889)
			(size 0.508 0.508)
			(layers "B.Cu" "B.Mask" "B.Paste")
			(net "CLK_25M_CPLD")
		)
		(zone
			(layer "B.Cu")
			(hatch none 0.5)
			(connect_pads
				(clearance 0)
			)
			(min_thickness 0.25)
			(keepout
				(tracks not_allowed)
				(vias allowed)
				(pads allowed)
				(copperpour not_allowed)
				(footprints allowed)
			)
			(placement
				(enabled no)
				(sheetname "")
			)
			(fill
				(thermal_gap 0.5)
				(thermal_bridge_width 0.5)
				(island_removal_mode 0)
			)
			(polygon
				(pts
					(xy 481.711 -33.147) (xy 482.219 -33.147) (xy 482.219 -32.766) (xy 481.711 -32.766)
				)
			)
		)
		(zone
			(layer "B.Cu")
			(hatch none 0.5)
			(connect_pads
				(clearance 0)
			)
			(min_thickness 0.25)
			(keepout
				(tracks allowed)
				(vias not_allowed)
				(pads allowed)
				(copperpour not_allowed)
				(footprints allowed)
			)
			(placement
				(enabled no)
				(sheetname "")
			)
			(fill
				(thermal_gap 0.5)
				(thermal_bridge_width 0.5)
				(island_removal_mode 0)
			)
			(polygon
				(pts
					(xy 481.711 -32.766) (xy 482.219 -32.766) (xy 482.219 -33.147) (xy 481.711 -33.147)
				)
			)
		)
	)
	(footprint ""
		(layer "B.Cu")
		(at 385.34594 -29.555694 90)
		(property "Reference" "C2T11"
			(at 0 0 90)
			(layer "B.SilkS")
			(hide yes)
			(effects
				(font
					(size 1.27 1.27)
				)
				(justify mirror)
			)
		)
		(property "Value" ""
			(at 0 0 90)
			(layer "B.Fab")
			(effects
				(font
					(size 1.27 1.27)
				)
				(justify mirror)
			)
		)
		(duplicate_pad_numbers_are_jumpers no)
		(fp_poly
			(pts
				(xy -0.3048 -0.1016) (xy -0.3048 0.9906) (xy 0.3048 0.9906) (xy 0.3048 -0.1016)
			)
			(stroke
				(width 0)
				(type default)
			)
			(fill no)
			(layer "B.CrtYd")
		)
		(fp_line
			(start 0.3048 -0.1016)
			(end 0.3048 0.9906)
			(stroke
				(width 0.1)
				(type default)
			)
			(layer "B.Fab")
		)
		(fp_line
			(start -0.3048 -0.1016)
			(end 0.3048 -0.1016)
			(stroke
				(width 0.1)
				(type default)
			)
			(layer "B.Fab")
		)
		(fp_line
			(start 0.3048 0.9906)
			(end -0.3048 0.9906)
			(stroke
				(width 0.1)
				(type default)
			)
			(layer "B.Fab")
		)
		(fp_line
			(start -0.3048 0.9906)
			(end -0.3048 -0.1016)
			(stroke
				(width 0.1)
				(type default)
			)
			(layer "B.Fab")
		)
		(pad "1" smd rect
			(at 0 0 270)
			(size 0.508 0.508)
			(layers "B.Cu" "B.Mask" "B.Paste")
			(net "P3E_PCH_M2_TX_C_DN<1>")
		)
		(pad "2" smd rect
			(at 0 0.889 270)
			(size 0.508 0.508)
			(layers "B.Cu" "B.Mask" "B.Paste")
			(net "P3E_PCH_M2_TX_DN<1>")
		)
		(zone
			(layer "B.Cu")
			(hatch none 0.5)
			(connect_pads
				(clearance 0)
			)
			(min_thickness 0.25)
			(keepout
				(tracks allowed)
				(vias not_allowed)
				(pads allowed)
				(copperpour not_allowed)
				(footprints allowed)
			)
			(placement
				(enabled no)
				(sheetname "")
			)
			(fill
				(thermal_gap 0.5)
				(thermal_bridge_width 0.5)
				(island_removal_mode 0)
			)
			(polygon
				(pts
					(xy 385.59994 -29.809694) (xy 385.59994 -29.301694) (xy 385.98094 -29.301694) (xy 385.98094 -29.809694)
				)
			)
		)
		(zone
			(layer "B.Cu")
			(hatch none 0.5)
			(connect_pads
				(clearance 0)
			)
			(min_thickness 0.25)
			(keepout
				(tracks not_allowed)
				(vias allowed)
				(pads allowed)
				(copperpour not_allowed)
				(footprints allowed)
			)
			(placement
				(enabled no)
				(sheetname "")
			)
			(fill
				(thermal_gap 0.5)
				(thermal_bridge_width 0.5)
				(island_removal_mode 0)
			)
			(polygon
				(pts
					(xy 385.98094 -29.809694) (xy 385.98094 -29.301694) (xy 385.59994 -29.301694) (xy 385.59994 -29.809694)
				)
			)
		)
	)
	(footprint ""
		(layer "B.Cu")
		(at 414.528 -20.3962 -90)
		(property "Reference" "R1U7"
			(at 0 0 90)
			(layer "B.SilkS")
			(hide yes)
			(effects
				(font
					(size 1.27 1.27)
				)
				(justify mirror)
			)
		)
		(property "Value" ""
			(at 0 0 90)
			(layer "B.Fab")
			(effects
				(font
					(size 1.27 1.27)
				)
				(justify mirror)
			)
		)
		(duplicate_pad_numbers_are_jumpers no)
		(fp_poly
			(pts
				(xy 0.2794 -0.1016) (xy -0.2794 -0.1016) (xy -0.2794 0.9906) (xy 0.2794 0.9906)
			)
			(stroke
				(width 0)
				(type default)
			)
			(fill no)
			(layer "B.CrtYd")
		)
		(fp_line
			(start -0.2794 0.9906)
			(end -0.2794 -0.1016)
			(stroke
				(width 0.1)
				(type default)
			)
			(layer "B.Fab")
		)
		(fp_line
			(start 0.2794 0.9906)
			(end -0.2794 0.9906)
			(stroke
				(width 0.1)
				(type default)
			)
			(layer "B.Fab")
		)
		(fp_line
			(start -0.2794 -0.1016)
			(end 0.2794 -0.1016)
			(stroke
				(width 0.1)
				(type default)
			)
			(layer "B.Fab")
		)
		(fp_line
			(start 0.2794 -0.1016)
			(end 0.2794 0.9906)
			(stroke
				(width 0.1)
				(type default)
			)
			(layer "B.Fab")
		)
		(pad "1" smd rect
			(at 0 0 90)
			(size 0.508 0.508)
			(layers "B.Cu" "B.Mask" "B.Paste")
			(net "GND")
		)
		(pad "2" smd rect
			(at 0 0.889 90)
			(size 0.508 0.508)
			(layers "B.Cu" "B.Mask" "B.Paste")
			(net "PD_SP_ENTEST")
		)
		(zone
			(layer "B.Cu")
			(hatch none 0.5)
			(connect_pads
				(clearance 0)
			)
			(min_thickness 0.25)
			(keepout
				(tracks not_allowed)
				(vias allowed)
				(pads allowed)
				(copperpour not_allowed)
				(footprints allowed)
			)
			(placement
				(enabled no)
				(sheetname "")
			)
			(fill
				(thermal_gap 0.5)
				(thermal_bridge_width 0.5)
				(island_removal_mode 0)
			)
			(polygon
				(pts
					(xy 413.893 -20.1422) (xy 413.893 -20.6502) (xy 414.274 -20.6502) (xy 414.274 -20.1422)
				)
			)
		)
		(zone
			(layer "B.Cu")
			(hatch none 0.5)
			(connect_pads
				(clearance 0)
			)
			(min_thickness 0.25)
			(keepout
				(tracks allowed)
				(vias not_allowed)
				(pads allowed)
				(copperpour not_allowed)
				(footprints allowed)
			)
			(placement
				(enabled no)
				(sheetname "")
			)
			(fill
				(thermal_gap 0.5)
				(thermal_bridge_width 0.5)
				(island_removal_mode 0)
			)
			(polygon
				(pts
					(xy 414.274 -20.1422) (xy 414.274 -20.6502) (xy 413.893 -20.6502) (xy 413.893 -20.1422)
				)
			)
		)
	)
)
